# T6G (Grand Teton) — schematic netlist excerpt (pin names and nets, part order shuffled) for the footprints in the layout excerpt that follows; sources: Cadence DE-HDL packaged netlist, KiCad conversion of 04192023_DAF0TMB3IC0_F0TG_MB_C_brd_V02_OCP.brd

C32  Q_CAP  0.1UF 25V 10% X7R  pkg 0402  page 235 : A = P3V3_AUX ; B = GND
R480  Q_RES  100K 1% CHIP  pkg 0402LF  page 188 : A = PWRGD_P5V_R ; B = GND

(kicad_pcb
	(version 20260206)
	(generator "pcbnew")
	(generator_version "10.0")
	(general
		(thickness 1.6)
		(legacy_teardrops no)
	)
	(paper "A4")
	(title_block
		(title "04192023_DAF0TMB3IC0_F0TG_MB_C_brd_V02_OCP.brd")
		(comment 1 "Grand Teton / footprints 3372-3373 of 8354")
	)
	(layers
		(0 "F.Cu" signal "TOP")
		(4 "In1.Cu" signal "GND")
		(6 "In2.Cu" signal "IN1")
		(8 "In3.Cu" signal "GND1")
		(10 "In4.Cu" signal "IN2")
		(12 "In5.Cu" signal "GND2")
		(14 "In6.Cu" signal "IN3")
		(16 "In7.Cu" signal "GND3")
		(18 "In8.Cu" signal "VCC")
		(20 "In9.Cu" signal "VCC1")
		(22 "In10.Cu" signal "GND4")
		(24 "In11.Cu" signal "IN4")
		(26 "In12.Cu" signal "GND5")
		(28 "In13.Cu" signal "IN5")
		(30 "In14.Cu" signal "GND6")
		(32 "In15.Cu" signal "IN6")
		(34 "In16.Cu" signal "GND7")
		(2 "B.Cu" signal "BOTTOM")
		(9 "F.Adhes" user "F.Adhesive")
		(11 "B.Adhes" user "B.Adhesive")
		(13 "F.Paste" user "Package Geometry/Pastemask Top")
		(15 "B.Paste" user "Package Geometry/Pastemask Bottom")
		(5 "F.SilkS" user "Ref Des/Silkscreen Top")
		(7 "B.SilkS" user "Ref Des/Silkscreen Bottom")
		(1 "F.Mask" user "Board Geometry/Soldermask Top")
		(3 "B.Mask" user "Board Geometry/Soldermask Bottom")
		(17 "Dwgs.User" user "User.Drawings")
		(19 "Cmts.User" user "User.Comments")
		(21 "Eco1.User" user "User.Eco1")
		(23 "Eco2.User" user "User.Eco2")
		(25 "Edge.Cuts" user "Board Geometry/Outline")
		(27 "Margin" user)
		(31 "F.CrtYd" user "Package Geometry/Place Bound Top")
		(29 "B.CrtYd" user "Package Geometry/Place Bound Bottom")
		(35 "F.Fab" user "Ref Des/Assembly Top")
		(33 "B.Fab" user "Ref Des/Assembly Bottom")
	)
	(footprint ""
		(layer "F.Cu")
		(at 169.418 -134.493)
		(property "Reference" "R480"
			(at 0 0 0)
			(layer "F.SilkS")
			(hide yes)
			(effects
				(font
					(size 1.27 1.27)
				)
			)
		)
		(property "Value" ""
			(at 0 0 0)
			(layer "F.Fab")
			(effects
				(font
					(size 1.27 1.27)
				)
			)
		)
		(duplicate_pad_numbers_are_jumpers no)
		(fp_line
			(start -0.7874 -0.4064)
			(end 0.7874 -0.4064)
			(stroke
				(width 0.1524)
				(type default)
			)
			(layer "F.SilkS")
		)
		(fp_line
			(start -0.7874 0.4064)
			(end -0.7874 -0.4064)
			(stroke
				(width 0.1524)
				(type default)
			)
			(layer "F.SilkS")
		)
		(fp_line
			(start 0.7874 -0.4064)
			(end 0.7874 0.4064)
			(stroke
				(width 0.1524)
				(type default)
			)
			(layer "F.SilkS")
		)
		(fp_line
			(start 0.7874 0.4064)
			(end -0.7874 0.4064)
			(stroke
				(width 0.1524)
				(type default)
			)
			(layer "F.SilkS")
		)
		(fp_line
			(start -0.67945 -0.305054)
			(end -0.12065 -0.305054)
			(stroke
				(width 0.1)
				(type default)
			)
			(layer "F.Fab")
		)
		(fp_line
			(start -0.67945 0.3048)
			(end -0.67945 -0.305054)
			(stroke
				(width 0.1)
				(type default)
			)
			(layer "F.Fab")
		)
		(fp_line
			(start -0.12065 -0.305054)
			(end -0.12065 -0.2794)
			(stroke
				(width 0.1)
				(type default)
			)
			(layer "F.Fab")
		)
		(fp_line
			(start -0.12065 -0.2794)
			(end 0.12065 -0.2794)
			(stroke
				(width 0.1)
				(type default)
			)
			(layer "F.Fab")
		)
		(fp_line
			(start -0.12065 0.2794)
			(end -0.12065 0.3048)
			(stroke
				(width 0.1)
				(type default)
			)
			(layer "F.Fab")
		)
		(fp_line
			(start -0.12065 0.3048)
			(end -0.67945 0.3048)
			(stroke
				(width 0.1)
				(type default)
			)
			(layer "F.Fab")
		)
		(fp_line
			(start 0.120396 0.2794)
			(end -0.12065 0.2794)
			(stroke
				(width 0.1)
				(type default)
			)
			(layer "F.Fab")
		)
		(fp_line
			(start 0.120396 0.3048)
			(end 0.120396 0.2794)
			(stroke
				(width 0.1)
				(type default)
			)
			(layer "F.Fab")
		)
		(fp_line
			(start 0.12065 -0.3048)
			(end 0.67945 -0.3048)
			(stroke
				(width 0.1)
				(type default)
			)
			(layer "F.Fab")
		)
		(fp_line
			(start 0.12065 -0.2794)
			(end 0.12065 -0.3048)
			(stroke
				(width 0.1)
				(type default)
			)
			(layer "F.Fab")
		)
		(fp_line
			(start 0.67945 -0.3048)
			(end 0.67945 0.3048)
			(stroke
				(width 0.1)
				(type default)
			)
			(layer "F.Fab")
		)
		(fp_line
			(start 0.67945 0.3048)
			(end 0.120396 0.3048)
			(stroke
				(width 0.1)
				(type default)
			)
			(layer "F.Fab")
		)
		(pad "1" smd circle
			(at -0.40005 0)
			(size 0 0)
			(layers "F.Cu" "F.Mask" "F.Paste")
			(net "PWRGD_P5V_R")
		)
		(pad "2" smd circle
			(at 0.40005 0)
			(size 0 0)
			(layers "F.Cu" "F.Mask" "F.Paste")
			(net "GND")
		)
	)
	(footprint ""
		(layer "F.Cu")
		(at 97.745296 -422.43248 90)
		(property "Reference" "C32"
			(at 0 0 90)
			(layer "F.SilkS")
			(hide yes)
			(effects
				(font
					(size 1.27 1.27)
				)
			)
		)
		(property "Value" ""
			(at 0 0 90)
			(layer "F.Fab")
			(effects
				(font
					(size 1.27 1.27)
				)
			)
		)
		(duplicate_pad_numbers_are_jumpers no)
		(fp_line
			(start 0.7874 -0.4064)
			(end 0.7874 0.4064)
			(stroke
				(width 0.1524)
				(type default)
			)
			(layer "F.SilkS")
		)
		(fp_line
			(start -0.7874 -0.4064)
			(end 0.7874 -0.4064)
			(stroke
				(width 0.1524)
				(type default)
			)
			(layer "F.SilkS")
		)
		(fp_line
			(start 0.7874 0.4064)
			(end -0.7874 0.4064)
			(stroke
				(width 0.1524)
				(type default)
			)
			(layer "F.SilkS")
		)
		(fp_line
			(start -0.7874 0.4064)
			(end -0.7874 -0.4064)
			(stroke
				(width 0.1524)
				(type default)
			)
			(layer "F.SilkS")
		)
		(fp_line
			(start -0.12065 -0.305054)
			(end -0.12065 -0.2794)
			(stroke
				(width 0.1)
				(type default)
			)
			(layer "F.Fab")
		)
		(fp_line
			(start -0.67945 -0.305054)
			(end -0.12065 -0.305054)
			(stroke
				(width 0.1)
				(type default)
			)
			(layer "F.Fab")
		)
		(fp_line
			(start 0.67945 -0.3048)
			(end 0.67945 0.3048)
			(stroke
				(width 0.1)
				(type default)
			)
			(layer "F.Fab")
		)
		(fp_line
			(start 0.12065 -0.3048)
			(end 0.67945 -0.3048)
			(stroke
				(width 0.1)
				(type default)
			)
			(layer "F.Fab")
		)
		(fp_line
			(start 0.12065 -0.2794)
			(end 0.12065 -0.3048)
			(stroke
				(width 0.1)
				(type default)
			)
			(layer "F.Fab")
		)
		(fp_line
			(start -0.12065 -0.2794)
			(end 0.12065 -0.2794)
			(stroke
				(width 0.1)
				(type default)
			)
			(layer "F.Fab")
		)
		(fp_line
			(start 0.120396 0.2794)
			(end -0.12065 0.2794)
			(stroke
				(width 0.1)
				(type default)
			)
			(layer "F.Fab")
		)
		(fp_line
			(start -0.12065 0.2794)
			(end -0.12065 0.3048)
			(stroke
				(width 0.1)
				(type default)
			)
			(layer "F.Fab")
		)
		(fp_line
			(start 0.67945 0.3048)
			(end 0.120396 0.3048)
			(stroke
				(width 0.1)
				(type default)
			)
			(layer "F.Fab")
		)
		(fp_line
			(start 0.120396 0.3048)
			(end 0.120396 0.2794)
			(stroke
				(width 0.1)
				(type default)
			)
			(layer "F.Fab")
		)
		(fp_line
			(start -0.12065 0.3048)
			(end -0.67945 0.3048)
			(stroke
				(width 0.1)
				(type default)
			)
			(layer "F.Fab")
		)
		(fp_line
			(start -0.67945 0.3048)
			(end -0.67945 -0.305054)
			(stroke
				(width 0.1)
				(type default)
			)
			(layer "F.Fab")
		)
		(pad "1" smd circle
			(at -0.40005 0 90)
			(size 0 0)
			(layers "F.Cu" "F.Mask" "F.Paste")
			(net "P3V3_AUX")
		)
		(pad "2" smd circle
			(at 0.40005 0 90)
			(size 0 0)
			(layers "F.Cu" "F.Mask" "F.Paste")
			(net "GND")
		)
	)
)
